(kicad_pcb
	(version 20260206)
	(generator "pcbnew")
	(generator_version "10.0")
	(general
		(thickness 1.6)
		(legacy_teardrops no)
	)
	(paper "A4")
	(title_block
		(title "9052_F0T_PDB_Converter_Brick_F_V03_1208_1600_OCP.brd")
		(comment 1 "Grand Teton / footprints 331-335 of 578")
	)
	(layers
		(0 "F.Cu" signal "TOP")
		(4 "In1.Cu" signal "GND")
		(6 "In2.Cu" signal "IN1")
		(8 "In3.Cu" signal "GND1")
		(10 "In4.Cu" signal "VCC")
		(12 "In5.Cu" signal "VCC1")
		(14 "In6.Cu" signal "GND2")
		(16 "In7.Cu" signal "IN2")
		(18 "In8.Cu" signal "GND3")
		(2 "B.Cu" signal "BOTTOM")
		(9 "F.Adhes" user "F.Adhesive")
		(11 "B.Adhes" user "B.Adhesive")
		(13 "F.Paste" user "Package Geometry/Pastemask Top")
		(15 "B.Paste" user "Package Geometry/Pastemask Bottom")
		(5 "F.SilkS" user "Ref Des/Silkscreen Top")
		(7 "B.SilkS" user "Ref Des/Silkscreen Bottom")
		(1 "F.Mask" user "Board Geometry/Soldermask Top")
		(3 "B.Mask" user "Board Geometry/Soldermask Bottom")
		(17 "Dwgs.User" user "User.Drawings")
		(19 "Cmts.User" user "User.Comments")
		(21 "Eco1.User" user "User.Eco1")
		(23 "Eco2.User" user "User.Eco2")
		(25 "Edge.Cuts" user "Board Geometry/Outline")
		(27 "Margin" user)
		(31 "F.CrtYd" user "Package Geometry/Place Bound Top")
		(29 "B.CrtYd" user "Package Geometry/Place Bound Bottom")
		(35 "F.Fab" user "Ref Des/Assembly Top")
		(33 "B.Fab" user "Ref Des/Assembly Bottom")
	)
	(footprint ""
		(layer "B.Cu")
		(at 276.733 -43.434)
		(property "Reference" "PC11"
			(at 0 0 0)
			(layer "B.SilkS")
			(hide yes)
			(effects
				(font
					(size 1.27 1.27)
				)
				(justify mirror)
			)
		)
		(property "Value" ""
			(at 0 0 0)
			(layer "B.Fab")
			(effects
				(font
					(size 1.27 1.27)
				)
				(justify mirror)
			)
		)
		(duplicate_pad_numbers_are_jumpers no)
		(fp_line
			(start -0.7874 -0.4064)
			(end -0.7874 0.4064)
			(stroke
				(width 0.1524)
				(type default)
			)
			(layer "B.SilkS")
		)
		(fp_line
			(start -0.7874 0.4064)
			(end 0.7874 0.4064)
			(stroke
				(width 0.1524)
				(type default)
			)
			(layer "B.SilkS")
		)
		(fp_line
			(start 0.7874 -0.4064)
			(end -0.7874 -0.4064)
			(stroke
				(width 0.1524)
				(type default)
			)
			(layer "B.SilkS")
		)
		(fp_line
			(start 0.7874 0.4064)
			(end 0.7874 -0.4064)
			(stroke
				(width 0.1524)
				(type default)
			)
			(layer "B.SilkS")
		)
		(fp_line
			(start -0.67945 -0.3048)
			(end -0.67945 0.3048)
			(stroke
				(width 0.1)
				(type default)
			)
			(layer "B.Fab")
		)
		(fp_line
			(start -0.67945 0.3048)
			(end -0.120396 0.3048)
			(stroke
				(width 0.1)
				(type default)
			)
			(layer "B.Fab")
		)
		(fp_line
			(start -0.12065 -0.3048)
			(end -0.67945 -0.3048)
			(stroke
				(width 0.1)
				(type default)
			)
			(layer "B.Fab")
		)
		(fp_line
			(start -0.12065 -0.2794)
			(end -0.12065 -0.3048)
			(stroke
				(width 0.1)
				(type default)
			)
			(layer "B.Fab")
		)
		(fp_line
			(start -0.120396 0.2794)
			(end 0.12065 0.2794)
			(stroke
				(width 0.1)
				(type default)
			)
			(layer "B.Fab")
		)
		(fp_line
			(start -0.120396 0.3048)
			(end -0.120396 0.2794)
			(stroke
				(width 0.1)
				(type default)
			)
			(layer "B.Fab")
		)
		(fp_line
			(start 0.12065 -0.305054)
			(end 0.12065 -0.2794)
			(stroke
				(width 0.1)
				(type default)
			)
			(layer "B.Fab")
		)
		(fp_line
			(start 0.12065 -0.2794)
			(end -0.12065 -0.2794)
			(stroke
				(width 0.1)
				(type default)
			)
			(layer "B.Fab")
		)
		(fp_line
			(start 0.12065 0.2794)
			(end 0.12065 0.3048)
			(stroke
				(width 0.1)
				(type default)
			)
			(layer "B.Fab")
		)
		(fp_line
			(start 0.12065 0.3048)
			(end 0.67945 0.3048)
			(stroke
				(width 0.1)
				(type default)
			)
			(layer "B.Fab")
		)
		(fp_line
			(start 0.67945 -0.305054)
			(end 0.12065 -0.305054)
			(stroke
				(width 0.1)
				(type default)
			)
			(layer "B.Fab")
		)
		(fp_line
			(start 0.67945 0.3048)
			(end 0.67945 -0.305054)
			(stroke
				(width 0.1)
				(type default)
			)
			(layer "B.Fab")
		)
		(pad "1" smd circle
			(at 0.40005 0 180)
			(size 0 0)
			(layers "B.Cu" "B.Mask" "B.Paste")
			(net "P52V_HS1_ESTART")
		)
		(pad "2" smd circle
			(at -0.40005 0 180)
			(size 0 0)
			(layers "B.Cu" "B.Mask" "B.Paste")
			(net "GND_FIELD_SIGNAL")
		)
	)
	(footprint ""
		(layer "B.Cu")
		(at 232.283 -75.184 -90)
		(property "Reference" "R187"
			(at 0 0 90)
			(layer "B.SilkS")
			(hide yes)
			(effects
				(font
					(size 1.27 1.27)
				)
				(justify mirror)
			)
		)
		(property "Value" ""
			(at 0 0 90)
			(layer "B.Fab")
			(effects
				(font
					(size 1.27 1.27)
				)
				(justify mirror)
			)
		)
		(duplicate_pad_numbers_are_jumpers no)
		(fp_line
			(start -0.7874 0.4064)
			(end 0.7874 0.4064)
			(stroke
				(width 0.1524)
				(type default)
			)
			(layer "B.SilkS")
		)
		(fp_line
			(start 0.7874 0.4064)
			(end 0.7874 -0.4064)
			(stroke
				(width 0.1524)
				(type default)
			)
			(layer "B.SilkS")
		)
		(fp_line
			(start -0.7874 -0.4064)
			(end -0.7874 0.4064)
			(stroke
				(width 0.1524)
				(type default)
			)
			(layer "B.SilkS")
		)
		(fp_line
			(start 0.7874 -0.4064)
			(end -0.7874 -0.4064)
			(stroke
				(width 0.1524)
				(type default)
			)
			(layer "B.SilkS")
		)
		(fp_line
			(start -0.67945 0.3048)
			(end -0.120396 0.3048)
			(stroke
				(width 0.1)
				(type default)
			)
			(layer "B.Fab")
		)
		(fp_line
			(start -0.120396 0.3048)
			(end -0.120396 0.2794)
			(stroke
				(width 0.1)
				(type default)
			)
			(layer "B.Fab")
		)
		(fp_line
			(start 0.12065 0.3048)
			(end 0.67945 0.3048)
			(stroke
				(width 0.1)
				(type default)
			)
			(layer "B.Fab")
		)
		(fp_line
			(start 0.67945 0.3048)
			(end 0.67945 -0.305054)
			(stroke
				(width 0.1)
				(type default)
			)
			(layer "B.Fab")
		)
		(fp_line
			(start -0.120396 0.2794)
			(end 0.12065 0.2794)
			(stroke
				(width 0.1)
				(type default)
			)
			(layer "B.Fab")
		)
		(fp_line
			(start 0.12065 0.2794)
			(end 0.12065 0.3048)
			(stroke
				(width 0.1)
				(type default)
			)
			(layer "B.Fab")
		)
		(fp_line
			(start -0.12065 -0.2794)
			(end -0.12065 -0.3048)
			(stroke
				(width 0.1)
				(type default)
			)
			(layer "B.Fab")
		)
		(fp_line
			(start 0.12065 -0.2794)
			(end -0.12065 -0.2794)
			(stroke
				(width 0.1)
				(type default)
			)
			(layer "B.Fab")
		)
		(fp_line
			(start -0.67945 -0.3048)
			(end -0.67945 0.3048)
			(stroke
				(width 0.1)
				(type default)
			)
			(layer "B.Fab")
		)
		(fp_line
			(start -0.12065 -0.3048)
			(end -0.67945 -0.3048)
			(stroke
				(width 0.1)
				(type default)
			)
			(layer "B.Fab")
		)
		(fp_line
			(start 0.12065 -0.305054)
			(end 0.12065 -0.2794)
			(stroke
				(width 0.1)
				(type default)
			)
			(layer "B.Fab")
		)
		(fp_line
			(start 0.67945 -0.305054)
			(end 0.12065 -0.305054)
			(stroke
				(width 0.1)
				(type default)
			)
			(layer "B.Fab")
		)
		(pad "1" smd circle
			(at 0.40005 0 90)
			(size 0 0)
			(layers "B.Cu" "B.Mask" "B.Paste")
			(net "GND")
		)
		(pad "2" smd circle
			(at -0.40005 0 90)
			(size 0 0)
			(layers "B.Cu" "B.Mask" "B.Paste")
			(net "PWRGD_P3V3_AUX_MB_R1")
		)
	)
	(footprint ""
		(layer "B.Cu")
		(at 221.615 -83.439 -90)
		(property "Reference" "U10"
			(at 1.016 -3.14833 270)
			(unlocked yes)
			(layer "B.SilkS")
			(effects
				(font
					(size 0.7874 0.5842)
					(thickness 0.1524)
				)
				(justify left mirror)
			)
		)
		(property "Value" ""
			(at 0 0 90)
			(layer "B.Fab")
			(effects
				(font
					(size 1.27 1.27)
				)
				(justify mirror)
			)
		)
		(duplicate_pad_numbers_are_jumpers no)
		(fp_line
			(start -1.4224 2.5146)
			(end -1.4224 -2.5146)
			(stroke
				(width 0.1524)
				(type default)
			)
			(layer "B.SilkS")
		)
		(fp_line
			(start 1.4224 2.5146)
			(end -1.4224 2.5146)
			(stroke
				(width 0.1524)
				(type default)
			)
			(layer "B.SilkS")
		)
		(fp_line
			(start 0 -2.0574)
			(end 0.4572 -2.5146)
			(stroke
				(width 0.1524)
				(type default)
			)
			(layer "B.SilkS")
		)
		(fp_line
			(start -1.4224 -2.5146)
			(end -0.4572 -2.5146)
			(stroke
				(width 0.1524)
				(type default)
			)
			(layer "B.SilkS")
		)
		(fp_line
			(start -0.4572 -2.5146)
			(end 0 -2.0574)
			(stroke
				(width 0.1524)
				(type default)
			)
			(layer "B.SilkS")
		)
		(fp_line
			(start 0.4572 -2.5146)
			(end 1.4224 -2.5146)
			(stroke
				(width 0.1524)
				(type default)
			)
			(layer "B.SilkS")
		)
		(fp_line
			(start 1.4224 -2.5146)
			(end 1.4224 2.5146)
			(stroke
				(width 0.1524)
				(type default)
			)
			(layer "B.SilkS")
		)
		(fp_poly
			(pts
				(xy 2.575814 -2.8702) (xy 2.956814 -3.6322) (xy 2.194814 -3.6322)
			)
			(stroke
				(width 0)
				(type default)
			)
			(fill yes)
			(layer "B.SilkS")
		)
		(fp_line
			(start -2.0066 2.5146)
			(end -2.0066 2.112264)
			(stroke
				(width 0.1)
				(type default)
			)
			(layer "B.Fab")
		)
		(fp_line
			(start 2.0066 2.5146)
			(end -2.0066 2.5146)
			(stroke
				(width 0.1)
				(type default)
			)
			(layer "B.Fab")
		)
		(fp_line
			(start -2.642616 2.112264)
			(end -2.642616 -2.112264)
			(stroke
				(width 0.1)
				(type default)
			)
			(layer "B.Fab")
		)
		(fp_line
			(start -2.0066 2.112264)
			(end -2.642616 2.112264)
			(stroke
				(width 0.1)
				(type default)
			)
			(layer "B.Fab")
		)
		(fp_line
			(start 2.0066 2.112264)
			(end 2.0066 2.5146)
			(stroke
				(width 0.1)
				(type default)
			)
			(layer "B.Fab")
		)
		(fp_line
			(start 2.648712 2.112264)
			(end 2.0066 2.112264)
			(stroke
				(width 0.1)
				(type default)
			)
			(layer "B.Fab")
		)
		(fp_line
			(start -2.642616 -2.112264)
			(end -2.0066 -2.112264)
			(stroke
				(width 0.1)
				(type default)
			)
			(layer "B.Fab")
		)
		(fp_line
			(start -2.0066 -2.112264)
			(end -2.0066 -2.5146)
			(stroke
				(width 0.1)
				(type default)
			)
			(layer "B.Fab")
		)
		(fp_line
			(start 2.0066 -2.114804)
			(end 2.648712 -2.114804)
			(stroke
				(width 0.1)
				(type default)
			)
			(layer "B.Fab")
		)
		(fp_line
			(start 2.648712 -2.114804)
			(end 2.648712 2.112264)
			(stroke
				(width 0.1)
				(type default)
			)
			(layer "B.Fab")
		)
		(fp_line
			(start -2.0066 -2.5146)
			(end 2.0066 -2.5146)
			(stroke
				(width 0.1)
				(type default)
			)
			(layer "B.Fab")
		)
		(fp_line
			(start 2.0066 -2.5146)
			(end 2.0066 -2.114804)
			(stroke
				(width 0.1)
				(type default)
			)
			(layer "B.Fab")
		)
		(fp_poly
			(pts
				(xy 3.6322 -1.869186) (xy 4.3942 -1.488186) (xy 4.3942 -2.250186)
			)
			(stroke
				(width 0)
				(type default)
			)
			(fill yes)
			(layer "B.Fab")
		)
		(pad "1" smd rect
			(at 2.6416 -1.905 180)
			(size 0.5588 1.7272)
			(layers "B.Cu" "B.Mask" "B.Paste")
			(net "FRU_ADDR0")
		)
		(pad "2" smd rect
			(at 2.6416 -0.635 180)
			(size 0.5588 1.7272)
			(layers "B.Cu" "B.Mask" "B.Paste")
			(net "FRU_ADDR1")
		)
		(pad "3" smd rect
			(at 2.6416 0.635 180)
			(size 0.5588 1.7272)
			(layers "B.Cu" "B.Mask" "B.Paste")
			(net "FRU_ADDR2")
		)
		(pad "4" smd rect
			(at 2.6416 1.905 180)
			(size 0.5588 1.7272)
			(layers "B.Cu" "B.Mask" "B.Paste")
			(net "GND")
		)
		(pad "5" smd rect
			(at -2.6416 1.905 180)
			(size 0.5588 1.7272)
			(layers "B.Cu" "B.Mask" "B.Paste")
			(net "SMB_FRU_DAT")
		)
		(pad "6" smd rect
			(at -2.6416 0.635 180)
			(size 0.5588 1.7272)
			(layers "B.Cu" "B.Mask" "B.Paste")
			(net "SMB_FRU_CLK")
		)
		(pad "7" smd rect
			(at -2.6416 -0.635 180)
			(size 0.5588 1.7272)
			(layers "B.Cu" "B.Mask" "B.Paste")
			(net "FRU_WP_N")
		)
		(pad "8" smd rect
			(at -2.6416 -1.905 180)
			(size 0.5588 1.7272)
			(layers "B.Cu" "B.Mask" "B.Paste")
			(net "P3V3_AUX")
		)
	)
	(footprint ""
		(layer "B.Cu")
		(at 223.52 -75.057 -90)
		(property "Reference" "R45"
			(at 0 0 90)
			(layer "B.SilkS")
			(hide yes)
			(effects
				(font
					(size 1.27 1.27)
				)
				(justify mirror)
			)
		)
		(property "Value" ""
			(at 0 0 90)
			(layer "B.Fab")
			(effects
				(font
					(size 1.27 1.27)
				)
				(justify mirror)
			)
		)
		(duplicate_pad_numbers_are_jumpers no)
		(fp_line
			(start -0.7874 0.4064)
			(end 0.7874 0.4064)
			(stroke
				(width 0.1524)
				(type default)
			)
			(layer "B.SilkS")
		)
		(fp_line
			(start 0.7874 0.4064)
			(end 0.7874 -0.4064)
			(stroke
				(width 0.1524)
				(type default)
			)
			(layer "B.SilkS")
		)
		(fp_line
			(start -0.7874 -0.4064)
			(end -0.7874 0.4064)
			(stroke
				(width 0.1524)
				(type default)
			)
			(layer "B.SilkS")
		)
		(fp_line
			(start 0.7874 -0.4064)
			(end -0.7874 -0.4064)
			(stroke
				(width 0.1524)
				(type default)
			)
			(layer "B.SilkS")
		)
		(fp_line
			(start -0.67945 0.3048)
			(end -0.120396 0.3048)
			(stroke
				(width 0.1)
				(type default)
			)
			(layer "B.Fab")
		)
		(fp_line
			(start -0.120396 0.3048)
			(end -0.120396 0.2794)
			(stroke
				(width 0.1)
				(type default)
			)
			(layer "B.Fab")
		)
		(fp_line
			(start 0.12065 0.3048)
			(end 0.67945 0.3048)
			(stroke
				(width 0.1)
				(type default)
			)
			(layer "B.Fab")
		)
		(fp_line
			(start 0.67945 0.3048)
			(end 0.67945 -0.305054)
			(stroke
				(width 0.1)
				(type default)
			)
			(layer "B.Fab")
		)
		(fp_line
			(start -0.120396 0.2794)
			(end 0.12065 0.2794)
			(stroke
				(width 0.1)
				(type default)
			)
			(layer "B.Fab")
		)
		(fp_line
			(start 0.12065 0.2794)
			(end 0.12065 0.3048)
			(stroke
				(width 0.1)
				(type default)
			)
			(layer "B.Fab")
		)
		(fp_line
			(start -0.12065 -0.2794)
			(end -0.12065 -0.3048)
			(stroke
				(width 0.1)
				(type default)
			)
			(layer "B.Fab")
		)
		(fp_line
			(start 0.12065 -0.2794)
			(end -0.12065 -0.2794)
			(stroke
				(width 0.1)
				(type default)
			)
			(layer "B.Fab")
		)
		(fp_line
			(start -0.67945 -0.3048)
			(end -0.67945 0.3048)
			(stroke
				(width 0.1)
				(type default)
			)
			(layer "B.Fab")
		)
		(fp_line
			(start -0.12065 -0.3048)
			(end -0.67945 -0.3048)
			(stroke
				(width 0.1)
				(type default)
			)
			(layer "B.Fab")
		)
		(fp_line
			(start 0.12065 -0.305054)
			(end 0.12065 -0.2794)
			(stroke
				(width 0.1)
				(type default)
			)
			(layer "B.Fab")
		)
		(fp_line
			(start 0.67945 -0.305054)
			(end 0.12065 -0.305054)
			(stroke
				(width 0.1)
				(type default)
			)
			(layer "B.Fab")
		)
		(pad "1" smd circle
			(at 0.40005 0 90)
			(size 0 0)
			(layers "B.Cu" "B.Mask" "B.Paste")
			(net "GND")
		)
		(pad "2" smd circle
			(at -0.40005 0 90)
			(size 0 0)
			(layers "B.Cu" "B.Mask" "B.Paste")
			(net "FRU_ADDR0")
		)
	)
	(footprint ""
		(layer "B.Cu")
		(at 211.074 -69.723 -90)
		(property "Reference" "R90"
			(at 0 0 90)
			(layer "B.SilkS")
			(hide yes)
			(effects
				(font
					(size 1.27 1.27)
				)
				(justify mirror)
			)
		)
		(property "Value" ""
			(at 0 0 90)
			(layer "B.Fab")
			(effects
				(font
					(size 1.27 1.27)
				)
				(justify mirror)
			)
		)
		(duplicate_pad_numbers_are_jumpers no)
		(fp_line
			(start -0.7874 0.4064)
			(end 0.7874 0.4064)
			(stroke
				(width 0.1524)
				(type default)
			)
			(layer "B.SilkS")
		)
		(fp_line
			(start 0.7874 0.4064)
			(end 0.7874 -0.4064)
			(stroke
				(width 0.1524)
				(type default)
			)
			(layer "B.SilkS")
		)
		(fp_line
			(start -0.7874 -0.4064)
			(end -0.7874 0.4064)
			(stroke
				(width 0.1524)
				(type default)
			)
			(layer "B.SilkS")
		)
		(fp_line
			(start 0.7874 -0.4064)
			(end -0.7874 -0.4064)
			(stroke
				(width 0.1524)
				(type default)
			)
			(layer "B.SilkS")
		)
		(fp_line
			(start -0.67945 0.3048)
			(end -0.120396 0.3048)
			(stroke
				(width 0.1)
				(type default)
			)
			(layer "B.Fab")
		)
		(fp_line
			(start -0.120396 0.3048)
			(end -0.120396 0.2794)
			(stroke
				(width 0.1)
				(type default)
			)
			(layer "B.Fab")
		)
		(fp_line
			(start 0.12065 0.3048)
			(end 0.67945 0.3048)
			(stroke
				(width 0.1)
				(type default)
			)
			(layer "B.Fab")
		)
		(fp_line
			(start 0.67945 0.3048)
			(end 0.67945 -0.305054)
			(stroke
				(width 0.1)
				(type default)
			)
			(layer "B.Fab")
		)
		(fp_line
			(start -0.120396 0.2794)
			(end 0.12065 0.2794)
			(stroke
				(width 0.1)
				(type default)
			)
			(layer "B.Fab")
		)
		(fp_line
			(start 0.12065 0.2794)
			(end 0.12065 0.3048)
			(stroke
				(width 0.1)
				(type default)
			)
			(layer "B.Fab")
		)
		(fp_line
			(start -0.12065 -0.2794)
			(end -0.12065 -0.3048)
			(stroke
				(width 0.1)
				(type default)
			)
			(layer "B.Fab")
		)
		(fp_line
			(start 0.12065 -0.2794)
			(end -0.12065 -0.2794)
			(stroke
				(width 0.1)
				(type default)
			)
			(layer "B.Fab")
		)
		(fp_line
			(start -0.67945 -0.3048)
			(end -0.67945 0.3048)
			(stroke
				(width 0.1)
				(type default)
			)
			(layer "B.Fab")
		)
		(fp_line
			(start -0.12065 -0.3048)
			(end -0.67945 -0.3048)
			(stroke
				(width 0.1)
				(type default)
			)
			(layer "B.Fab")
		)
		(fp_line
			(start 0.12065 -0.305054)
			(end 0.12065 -0.2794)
			(stroke
				(width 0.1)
				(type default)
			)
			(layer "B.Fab")
		)
		(fp_line
			(start 0.67945 -0.305054)
			(end 0.12065 -0.305054)
			(stroke
				(width 0.1)
				(type default)
			)
			(layer "B.Fab")
		)
		(pad "1" smd circle
			(at 0.40005 0 90)
			(size 0 0)
			(layers "B.Cu" "B.Mask" "B.Paste")
			(net "P3V3_AUX")
		)
		(pad "2" smd circle
			(at -0.40005 0 90)
			(size 0 0)
			(layers "B.Cu" "B.Mask" "B.Paste")
			(net "SKU_ID_2")
		)
	)
)
